# BASEBOARD_FAB2 (Tioga Pass) — schematic parts with pin connectivity, parts 4650–4650 of 4751; source: Cadence DE-HDL packaged netlist (pstxprt.dat, pstxnet.dat, pstchip.dat)

U2D1  SKX_EXT_B  IC  pkg BGA1  page 55  (pins 1691-2028 of 3647)
  CR20  UPI2_RX_DP(8)  IN  = GND
  CR22  VSS(389)  GROUND  = GND
  CR24  VSS(388)  GROUND  = GND
  CR26  BCLK1_DN  IN  = CLK_100M_CPU1_BCLK1_DN
  CR28  DDR345_DRAM_PWR_OK  IN  = PWRGD_CPU1_DRAMPWROK_KLM_G
  CR30  PE3_RBIAS(1)  IN  = A_CPU1_PE3_RBIAS
  CR32  VSS(387)  GROUND  = GND
  CR34  VCCIN(18)  POWER  = PVCCIN_CPU1
  CR54  VCCIN(17)  POWER  = PVCCIN_CPU1
  CR56  VCCIN(16)  POWER  = PVCCIN_CPU1
  CR58  VSS(386)  GROUND  = GND
  CR60  RSVD(72)  BI  = TP_CPU1_RSVD_72
  CR62  VSS(385)  GROUND  = GND
  CR64  VSS(384)  GROUND  = GND
  CR66  VSS(383)  GROUND  = GND
  CR68  VSS(382)  GROUND  = GND
  CR74  DDR5_DQ(0)  BI  = M_M_DQ<0>
  CR76  DDR5_DQS_DP(0)  BI  = M_M_DQS_DP<0>
  CR78  VSS(381)  GROUND  = GND
  CR80  DDR4_DQ(6)  BI  = M_L_DQ<6>
  CR82  DDR4_DQ(3)  BI  = M_L_DQ<3>
  CR84  DDR3_DQS_DN(9)  BI  = M_K_DQS_DN<9>
  CR86  VSS(380)  GROUND  = GND
  CT1  PE2_TX_DN(2)  OUT  = TP_P3E_CPU1_PE2_RSR_TXN<2>
  CT3  PE2_TX_DN(3)  OUT  = TP_P3E_CPU1_PE2_RSR_TXN<3>
  CT5  RSVD(70)  BI  = TP_CPU1_RSVD_70
  CT7  VSS(1063)  GROUND  = GND
  CT9  PE2_RX_DN(0)  IN  = TP_P3E_CPU1_PE2_RSR_RXN<0>
  CT11  DMI_RX_DN(3)  IN  = TP_CPU1_DMI_RX_DN3
  CT13  VSS(378)  GROUND  = GND
  CT19  VSS(377)  GROUND  = GND
  CT21  UPI2_RX_DN(8)  IN  = GND
  CT23  RSVD(71)  BI  = PVCCMCP_CPU1
  CT25  BCLK2_DN  IN  = CLK_100M_CPU1_BCLK2_DN
  CT27  VSS(376)  GROUND  = GND
  CT29  VSS(375)  GROUND  = GND
  CT31  MCP01_RBIAS(1)  BI  = A_CPU1_MCP01_RBIAS
  CT33  VSS(374)  GROUND  = GND
  CT35  VSS(373)  GROUND  = GND
  CT37  VCCIN(15)  POWER  = PVCCIN_CPU1
  CT39  VCCIN(14)  POWER  = PVCCIN_CPU1
  CT41  VCCIN(13)  POWER  = PVCCIN_CPU1
  CT53  VCCIN(12)  POWER  = PVCCIN_CPU1
  CT55  VCCIN(11)  POWER  = PVCCIN_CPU1
  CT57  VSS(372)  GROUND  = GND
  CT59  SMBCLK  BI  = SMB_PIROM_CPU1_SCL
  CT61  DDR4_CAVREF  OUT  = M_L_CPU_VREF
  CT63  DDR5_DQ(27)  BI  = M_M_DQ<27>
  CT65  DDR5_DQS_DP(3)  BI  = M_M_DQS_DP<3>
  CT67  DDR5_DQ(29)  BI  = M_M_DQ<29>
  CT69  RSVD(69)  BI  = TP_CPU1_RSVD_69
  CT73  VSS(371)  GROUND  = GND
  CT75  DDR5_DQS_DN(9)  BI  = M_M_DQS_DN<9>
  CT77  DDR5_DQ(7)  BI  = M_M_DQ<7>
  CT79  VSS(370)  GROUND  = GND
  CT81  DDR4_DQ(2)  BI  = M_L_DQ<2>
  CT83  VSS(369)  GROUND  = GND
  CT85  VSS(368)  GROUND  = GND
  CU2  PE2_TX_DP(1)  OUT  = TP_P3E_CPU1_PE2_RSR_TXP<1>
  CU4  VSS(367)  GROUND  = GND
  CU6  RSVD(67)  BI  = TP_CPU1_RSVD_67
  CU8  PE1_RX_DP(0)  IN  = TP_P3E_CPU1_PE1_MP_RXP<0>
  CU10  PE3_RX_DP(15)  IN  = P3E_CPU1_PE3_MP_RXP<15>
  CU12  VCCIO(18)  POWER  = PVCCIO_CPU1
  CU14  UPI2_TX_DN(12)  OUT  = TP_CPU1_UPI2_RSVD_DD17
  CU18  VCCIO(16)  POWER  = PVCCIO_CPU1
  CU20  UPI2_RX_DP(6)  IN  = GND
  CU22  VSS(366)  GROUND  = GND
  CU24  RSVD(68)  BI  = PVCCMCP_CPU1
  CU26  BCLK2_DP  IN  = CLK_100M_CPU1_BCLK2_DP
  CU28  VSS(365)  GROUND  = GND
  CU30  VSS(364)  GROUND  = GND
  CU32  MCP01_RBIAS(0)  BI  = A_CPU1_MCP01_RBIAS
  CU34  VSS(363)  GROUND  = GND
  CU36  VSS(362)  GROUND  = GND
  CU38  VCCIN(10)  POWER  = PVCCIN_CPU1
  CU40  VCCIN(9)  POWER  = PVCCIN_CPU1
  CU42  VCCIN(8)  POWER  = PVCCIN_CPU1
  CU52  VCCIN(7)  POWER  = PVCCIN_CPU1
  CU54  VCCIN(6)  POWER  = PVCCIN_CPU1
  CU56  VSS(361)  GROUND  = GND
  CU58  PIROM_ADDR(0)  BI  = PU_PIROM_CPU1_ADDR0
  CU60  RSVD(66)  BI  = TP_CPU1_RSVD_66
  CU62  VSS(360)  GROUND  = GND
  CU64  DDR5_DQ(31)  BI  = M_M_DQ<31>
  CU66  DDR5_DQ(25)  BI  = M_M_DQ<25>
  CU68  VSS(359)  GROUND  = GND
  CU74  DDR5_DQS_DP(9)  BI  = M_M_DQS_DP<9>
  CU76  VSS(358)  GROUND  = GND
  CU78  VSS(357)  GROUND  = GND
  CU80  VSS(356)  GROUND  = GND
  CU82  VSS(355)  GROUND  = GND
  CU84  DDR3_DQS_DN(0)  BI  = M_K_DQS_DN<0>
  CU86  VSS(354)  GROUND  = GND
  CV1  VSS(353)  GROUND  = GND
  CV3  PE2_TX_DN(1)  OUT  = TP_P3E_CPU1_PE2_RSR_TXN<1>
  CV5  PE3_TX_DP(15)  OUT  = P3E_CPU1_PE3_MP_TXP<15>
  CV7  VCCIO(23)  POWER  = PVCCIO_CPU1
  CV9  PE3_RX_DN(15)  IN  = P3E_CPU1_PE3_MP_RXN<15>
  CV11  DMI_RX_DP(3)  IN  = TP_CPU1_DMI_RX_DP3
  CV13  UPI2_TX_DP(11)  OUT  = TP_CPU1_UPI2_RSVD_DD15
  CV17  VSS(351)  GROUND  = GND
  CV19  UPI2_RX_DN(7)  IN  = GND
  CV21  VCCIO(17)  POWER  = PVCCIO_CPU1
  CV23  RSVD(65)  BI  = PVCCMCP_CPU1
  CV25  VSS(350)  GROUND  = GND
  CV27  VSS(349)  GROUND  = GND
  CV29  DDR5_DQS_DP(16)  BI  = M_M_DQS_DP<16>
  CV31  VSS(348)  GROUND  = GND
  CV33  VSS(347)  GROUND  = GND
  CV35  DDR5_DQS_DP(15)  BI  = M_M_DQS_DP<15>
  CV37  VSS(346)  GROUND  = GND
  CV39  VSS(345)  GROUND  = GND
  CV41  VSS(344)  GROUND  = GND
  CV51  VCCIN(5)  POWER  = PVCCIN_CPU1
  CV53  VSS(343)  GROUND  = GND
  CV55  VSS(342)  GROUND  = GND
  CV57  PIROM_ADDR(1)  BI  = PD_PIROM_CPU1_ADDR1
  CV59  SM_WP  IN  = FM_CPU1_SM_WP
  CV61  DDR5_CAVREF  OUT  = M_M_CPU_VREF
  CV63  VSS(341)  GROUND  = GND
  CV65  DDR5_DQS_DN(3)  BI  = M_M_DQS_DN<3>
  CV67  VSS(340)  GROUND  = GND
  CV69  RSVD(64)  BI  = TP_CPU1_RSVD_64
  CV73  VSS(339)  GROUND  = GND
  CV75  DDR5_DQ(6)  BI  = M_M_DQ<6>
  CV77  DDR5_DQ(3)  BI  = M_M_DQ<3>
  CV79  VSS(338)  GROUND  = GND
  CV81  VSS(337)  GROUND  = GND
  CV83  VSS(336)  GROUND  = GND
  CV85  DDR3_DQS_DP(0)  BI  = M_K_DQS_DP<0>
  CW2  PE1_TX_DP(0)  OUT  = TP_P3E_CPU1_PE1_MP_TXP<0>
  CW4  PE2_TX_DP(0)  OUT  = TP_P3E_CPU1_PE2_RSR_TXP<0>
  CW6  VSS(1192)  GROUND  = GND
  CW8  PE1_RX_DN(0)  IN  = TP_P3E_CPU1_PE1_MP_RXN<0>
  CW10  PE3_RX_DP(14)  IN  = P3E_CPU1_PE3_MP_RXP<14>
  CW12  VSS(335)  GROUND  = GND
  CW14  UPI2_TX_DN(11)  OUT  = TP_CPU1_UPI2_RSVD_DF15
  CW16  UPI2_TX_DP(10)  OUT  = TP_CPU1_UPI2_RSVD_DB15
  CW18  UPI2_RX_DP(7)  IN  = GND
  CW20  UPI2_RX_DN(6)  IN  = GND
  CW22  RSVD(63)  BI  = TP_CPU1_KTI2_DFX_DN
  CW24  RSVD(62)  BI  = PVCCMCP_CPU1
  CW26  VSS(334)  GROUND  = GND
  CW28  DDR5_DQ(62)  BI  = M_M_DQ<62>
  CW30  DDR5_DQ(56)  BI  = M_M_DQ<56>
  CW32  VSS(333)  GROUND  = GND
  CW34  DDR5_DQ(54)  BI  = M_M_DQ<54>
  CW36  DDR5_DQ(48)  BI  = M_M_DQ<48>
  CW38  VSS(332)  GROUND  = GND
  CW40  VSS(331)  GROUND  = GND
  CW42  VSS(330)  GROUND  = GND
  CW46  VCCIN(4)  POWER  = PVCCIN_CPU1
  CW48  VCCIN(3)  POWER  = PVCCIN_CPU1
  CW50  VCCIN(2)  POWER  = PVCCIN_CPU1
  CW52  VSS(329)  GROUND  = GND
  CW54  VSS(328)  GROUND  = GND
  CW56  PIROM_ADDR(2)  BI  = PD_PIROM_CPU1_ADDR2
  CW58  SMBDAT  BI  = SMB_PIROM_CPU1_SDA
  CW60  RSVD(61)  BI  = TP_CPU1_RSVD_61
  CW62  RSVD(60)  BI  = TP_CPU1_RSVD_60
  CW64  VSS(327)  GROUND  = GND
  CW66  VSS(326)  GROUND  = GND
  CW68  VSS(325)  GROUND  = GND
  CW72  PKGID(1)  BI  = FM_CPU1_PKGID1
  CW74  VSS(324)  GROUND  = GND
  CW76  DDR5_DQ(2)  BI  = M_M_DQ<2>
  CW78  VSS(323)  GROUND  = GND
  CW80  DDR4_DQ(13)  BI  = M_L_DQ<13>
  CW82  VSS(322)  GROUND  = GND
  CW84  DDR3_DQ(7)  BI  = M_K_DQ<7>
  CW86  DDR3_DQ(6)  BI  = M_K_DQ<6>
  CY1  VSS(321)  GROUND  = GND
  CY3  PE2_TX_DN(0)  OUT  = TP_P3E_CPU1_PE2_RSR_TXN<0>
  CY5  PE3_TX_DN(15)  OUT  = P3E_CPU1_PE3_MP_TXN<15>
  CY7  PE1_RX_DP(1)  IN  = TP_P3E_CPU1_PE1_MP_RXP<1>
  CY9  VSS(320)  GROUND  = GND
  CY11  PE3_RX_DN(14)  IN  = P3E_CPU1_PE3_MP_RXN<14>
  CY13  VSS(319)  GROUND  = GND
  CY15  VSS(318)  GROUND  = GND
  CY17  VCCIO(15)  POWER  = PVCCIO_CPU1
  CY19  UPI2_RX_DP(5)  IN  = GND
  CY21  VSS(317)  GROUND  = GND
  CY23  RSVD(59)  BI  = TP_CPU1_RSVD_59
  CY25  RSVD(58)  BI  = PVCCMCP_CPU1
  CY27  DDR5_DQ(58)  BI  = M_M_DQ<58>
  CY29  DDR5_DQS_DN(16)  BI  = M_M_DQS_DN<16>
  CY31  DDR5_DQ(60)  BI  = M_M_DQ<60>
  CY33  DDR5_DQ(50)  BI  = M_M_DQ<50>
  CY35  DDR5_DQS_DN(15)  BI  = M_M_DQS_DN<15>
  CY37  DDR5_DQ(52)  BI  = M_M_DQ<52>
  CY39  RSVD(57)  BI  = TP_CPU1_RSVD_57
  CY41  VSS(316)  GROUND  = GND
  CY45  VSS(315)  GROUND  = GND
  CY47  VCCIN(1)  POWER  = PVCCIN_CPU1
  CY49  VCCIN(0)  POWER  = PVCCIN_CPU1
  CY51  VSS(314)  GROUND  = GND
  CY53  RSVD(56)  BI  = TP_CPU1_RSVD_56
  CY55  VCC33  POWER  = P3V3_STBY
  CY57  RSVD(55)  BI  = TP_CPU1_RSVD_55
  CY59  VSS(313)  GROUND  = GND
  CY61  VSS(312)  GROUND  = GND
  CY63  RSVD(54)  BI  = TP_CPU1_RSVD_54
  CY65  VSS(311)  GROUND  = GND
  CY67  DDR3_DQS_DP(17)  BI  = M_K_DQS_DP<17>
  CY69  VSS(310)  GROUND  = GND
  CY71  PROC_ID(0)  OUT  = FM_CPU1_PROC_ID0
  CY73  RSVD(53)  BI  = TP_CPU1_RSVD_53
  CY75  VSS(309)  GROUND  = GND
  CY77  VSS(308)  GROUND  = GND
  CY79  DDR4_DQ(12)  BI  = M_L_DQ<12>
  CY81  DDR4_DQ(9)  BI  = M_L_DQ<9>
  CY83  VSS(307)  GROUND  = GND
  CY85  VSS(306)  GROUND  = GND
  D3  VSS(1246)  GROUND  = GND
  D5  RSVD(287)  BI  = TP_CPU1_RSVD_287
  D7  VCCIO(25)  POWER  = PVCCIO_CPU1
  D9  UPI1_TX_DN(7)  OUT  = UPI_CPU1_CPU0_P1P1_DP<7>
  D11  VSS(1167)  GROUND  = GND
  D13  VSS(1166)  GROUND  = GND
  D15  UPI1_TX_DN(12)  OUT  = UPI_CPU1_CPU0_P1P1_DN<12>
  D17  RSVD(286)  BI  = TP_CPU1_RSVD_286
  D25  VSS(1165)  GROUND  = GND
  D27  VSS(1164)  GROUND  = GND
  D29  VSS(1163)  GROUND  = GND
  D31  VSS(1162)  GROUND  = GND
  D33  VSS(1161)  GROUND  = GND
  D35  VSS(1160)  GROUND  = GND
  D37  VSS(1159)  GROUND  = GND
  D39  VSS(1158)  GROUND  = GND
  D41  VSS(1157)  GROUND  = GND
  D43  VSS(1156)  GROUND  = GND
  D45  VCCD012(49)  POWER  = PVDDQ_GHJ
  D47  DDR0_CS_N(2)  OUT  = M_G_CS_N<2>
  D49  DDR0_CS_N(5)  OUT  = M_G_CS_N<5>
  D51  DDR0_MA(16)  OUT  = M_G_MA<16>
  D53  DDR0_PAR  OUT  = M_G_PAR
  D55  DDR0_CLK_DP(0)  OUT  = M_G_CLK_DP<0>
  D57  DDR0_MA(2)  OUT  = M_G_MA<2>
  D59  DDR0_MA(6)  OUT  = M_G_MA<6>
  D61  DDR0_BG(0)  OUT  = M_G_BG<0>
  D63  DDR0_CKE(3)  OUT  = M_G_CKE<3>
  D65  RSVD(285)  BI  = TP_CPU1_RSVD_285
  D71  DDR1_DQ(26)  BI  = M_H_DQ<26>
  D73  DDR1_DQS_DP(12)  BI  = M_H_DQS_DP<12>
  D75  DDR1_DQ(24)  BI  = M_H_DQ<24>
  D77  VSS(1155)  GROUND  = GND
  D79  DDR1_DQS_DN(11)  BI  = M_H_DQS_DN<11>
  D81  VSS(1245)  GROUND  = GND
  D83  RSVD(284)  BI  = TP_CPU1_RSVD_284
  DA2  PE1_TX_DN(0)  OUT  = TP_P3E_CPU1_PE1_MP_TXN<0>
  DA4  PE3_TX_DP(14)  OUT  = P3E_CPU1_PE3_MP_TXP<14>
  DA6  VSS(305)  GROUND  = GND
  DA8  PE1_RX_DN(1)  IN  = TP_P3E_CPU1_PE1_MP_RXN<1>
  DA10  PE1_RX_DP(3)  IN  = TP_P3E_CPU1_PE1_MP_RXP<3>
  DA12  PE3_RX_DP(13)  IN  = P3E_CPU1_PE3_MP_RXP<13>
  DA14  VCCIO(33)  POWER  = PVCCIO_CPU1
  DA16  UPI2_TX_DN(10)  OUT  = TP_CPU1_UPI2_RSVD_DC16
  DA18  VSS(303)  GROUND  = GND
  DA20  UPI2_RX_DN(5)  IN  = GND
  DA22  UPI2_RX_DP(2)  IN  = GND
  DA24  RSVD(52)  BI  = PVCCMCP_CPU1
  DA26  VSS(302)  GROUND  = GND
  DA28  VSS(301)  GROUND  = GND
  DA30  VSS(300)  GROUND  = GND
  DA32  VSS(299)  GROUND  = GND
  DA34  VSS(298)  GROUND  = GND
  DA36  VSS(297)  GROUND  = GND
  DA38  VSS(296)  GROUND  = GND
  DA40  RSVD(51)  BI  = TP_CPU1_RSVD_51
  DA42  DDR5_DQ(36)  BI  = M_M_DQ<36>
  DA44  VSS(295)  GROUND  = GND
  DA46  VSS(294)  GROUND  = GND
  DA48  VSS(293)  GROUND  = GND
  DA50  VSS(292)  GROUND  = GND
  DA52  RSVD(50)  BI  = TP_CPU1_RSVD_50
  DA54  RSVD(49)  BI  = TP_CPU1_RSVD_49
  DA56  RSVD(48)  BI  = TP_CPU1_RSVD_48
  DA58  DDR5_MA(9)  OUT  = M_M_MA<9>
  DA60  DDR5_MA(11)  OUT  = M_M_MA<11>
  DA62  DDR5_BG(0)  OUT  = M_M_BG<0>
  DA64  VSS(291)  GROUND  = GND
  DA66  DDR3_ECC(6)  BI  = M_K_ECC<6>
  DA68  DDR3_ECC(0)  BI  = M_K_ECC<0>
  DA70  VSS(290)  GROUND  = GND
  DA72  PKGID(2)  BI  = FM_CPU1_PKGID2
  DA74  VSS(289)  GROUND  = GND
  DA76  VSS(288)  GROUND  = GND
  DA78  VSS(287)  GROUND  = GND
  DA80  VSS(286)  GROUND  = GND
  DA82  DDR4_DQS_DN(1)  BI  = M_L_DQS_DN<1>
  DA84  DDR3_DQ(3)  BI  = M_K_DQ<3>
  DA86  DDR3_DQ(2)  BI  = M_K_DQ<2>
  DB1  PE1_TX_DP(1)  OUT  = TP_P3E_CPU1_PE1_MP_TXP<1>
  DB3  VSS(285)  GROUND  = GND
  DB5  PE3_TX_DN(14)  OUT  = P3E_CPU1_PE3_MP_TXN<14>
  DB7  VSS(1086)  GROUND  = GND
  DB9  PE1_RX_DP(2)  IN  = TP_P3E_CPU1_PE1_MP_RXP<2>
  DB11  PE3_RX_DN(13)  IN  = P3E_CPU1_PE3_MP_RXN<13>
  DB13  VSS(284)  GROUND  = GND
  DB15  UPI2_TX_DP(9)  OUT  = TP_CPU1_UPI2_RSVD_CW16
  DB17  VSS(283)  GROUND  = GND
  DB19  UPI2_RX_DP(4)  IN  = GND
  DB21  UPI2_RX_DN(3)  IN  = GND
  DB23  VSS(282)  GROUND  = GND
  DB25  VSS(281)  GROUND  = GND
  DB27  DDR5_DQ(59)  BI  = M_M_DQ<59>
  DB29  DDR5_DQS_DP(7)  BI  = M_M_DQS_DP<7>
  DB31  DDR5_DQ(61)  BI  = M_M_DQ<61>
  DB33  DDR5_DQ(51)  BI  = M_M_DQ<51>
  DB35  DDR5_DQS_DP(6)  BI  = M_M_DQS_DP<6>
  DB37  DDR5_DQ(53)  BI  = M_M_DQ<53>
  DB39  VSS(280)  GROUND  = GND
  DB41  VSS(279)  GROUND  = GND
  DB45  SVIDDATA(0)  BI  = SVID_DIO0_CPU1
  DB47  VSS(278)  GROUND  = GND
  DB49  VSS(277)  GROUND  = GND
  DB51  TEST_13  BI  = PD_CPU1_TEST13
  DB53  VCCD345(48)  POWER  = PVDDQ_KLM
  DB55  VCCD345(47)  POWER  = PVDDQ_KLM
  DB57  VCCD345(46)  POWER  = PVDDQ_KLM
  DB59  VCCD345(45)  POWER  = PVDDQ_KLM
  DB61  VCCD345(44)  POWER  = PVDDQ_KLM
  DB63  VCCD345(43)  POWER  = PVDDQ_KLM
  DB65  DDR3_ECC(2)  BI  = M_K_ECC<2>
  DB67  DDR3_DQS_DN(17)  BI  = M_K_DQS_DN<17>
  DB69  DDR3_ECC(4)  BI  = M_K_ECC<4>
  DB71  PROC_ID(1)  OUT  = FM_CPU1_PROC_ID1
  DB73  VSS(276)  GROUND  = GND
  DB75  DDR5_DQ(13)  BI  = M_M_DQ<13>
  DB77  VSS(275)  GROUND  = GND
  DB79  DDR4_DQ(8)  BI  = M_L_DQ<8>
  DB81  DDR4_DQS_DP(1)  BI  = M_L_DQS_DP<1>
  DB83  VSS(274)  GROUND  = GND
  DB85  VSS(273)  GROUND  = GND
  DC2  PE1_TX_DN(1)  OUT  = TP_P3E_CPU1_PE1_MP_TXN<1>
  DC4  PE1_TX_DP(3)  OUT  = TP_P3E_CPU1_PE1_MP_TXP<3>
  DC6  PE3_TX_DP(13)  OUT  = P3E_CPU1_PE3_MP_TXP<13>
